(kicad_pcb
	(version 20260206)
	(generator "pcbnew")
	(generator_version "10.0")
	(general
		(thickness 1.6)
		(legacy_teardrops no)
	)
	(paper "A4")
	(title_block
		(title "Wiwynn_Tioga_Pass_MB.brd")
		(comment 1 "Tioga Pass / footprints 3071-3078 of 4770")
	)
	(layers
		(0 "F.Cu" signal "TOP")
		(4 "In1.Cu" signal "L2GND")
		(6 "In2.Cu" signal "L3")
		(8 "In3.Cu" signal "L4GND")
		(10 "In4.Cu" signal "L5")
		(12 "In5.Cu" signal "L6GND")
		(14 "In6.Cu" signal "L7VCC")
		(16 "In7.Cu" signal "L8VCC")
		(18 "In8.Cu" signal "L9GND")
		(20 "In9.Cu" signal "L10")
		(22 "In10.Cu" signal "L11GND")
		(24 "In11.Cu" signal "L12")
		(26 "In12.Cu" signal "L13GND")
		(2 "B.Cu" signal "BOTTOM")
		(9 "F.Adhes" user "F.Adhesive")
		(11 "B.Adhes" user "B.Adhesive")
		(13 "F.Paste" user "Package Geometry/Pastemask Top")
		(15 "B.Paste" user "Package Geometry/Pastemask Bottom")
		(5 "F.SilkS" user "Ref Des/Silkscreen Top")
		(7 "B.SilkS" user "Ref Des/Silkscreen Bottom")
		(1 "F.Mask" user "Board Geometry/Soldermask Top")
		(3 "B.Mask" user "Board Geometry/Soldermask Bottom")
		(17 "Dwgs.User" user "User.Drawings")
		(19 "Cmts.User" user "User.Comments")
		(21 "Eco1.User" user "User.Eco1")
		(23 "Eco2.User" user "User.Eco2")
		(25 "Edge.Cuts" user "Board Geometry/Outline")
		(27 "Margin" user)
		(31 "F.CrtYd" user "Package Geometry/Place Bound Top")
		(29 "B.CrtYd" user "Package Geometry/Place Bound Bottom")
		(35 "F.Fab" user "Ref Des/Assembly Top")
		(33 "B.Fab" user "Ref Des/Assembly Bottom")
	)
	(footprint ""
		(layer "B.Cu")
		(at 499.3894 -140.843)
		(property "Reference" "R1L33"
			(at 0 0 0)
			(layer "B.SilkS")
			(hide yes)
			(effects
				(font
					(size 1.27 1.27)
				)
				(justify mirror)
			)
		)
		(property "Value" ""
			(at 0 0 0)
			(layer "B.Fab")
			(effects
				(font
					(size 1.27 1.27)
				)
				(justify mirror)
			)
		)
		(duplicate_pad_numbers_are_jumpers no)
		(fp_poly
			(pts
				(xy 0.2794 -0.1016) (xy -0.2794 -0.1016) (xy -0.2794 0.9906) (xy 0.2794 0.9906)
			)
			(stroke
				(width 0)
				(type default)
			)
			(fill no)
			(layer "B.CrtYd")
		)
		(fp_line
			(start -0.2794 -0.1016)
			(end 0.2794 -0.1016)
			(stroke
				(width 0.1)
				(type default)
			)
			(layer "B.Fab")
		)
		(fp_line
			(start -0.2794 0.9906)
			(end -0.2794 -0.1016)
			(stroke
				(width 0.1)
				(type default)
			)
			(layer "B.Fab")
		)
		(fp_line
			(start 0.2794 -0.1016)
			(end 0.2794 0.9906)
			(stroke
				(width 0.1)
				(type default)
			)
			(layer "B.Fab")
		)
		(fp_line
			(start 0.2794 0.9906)
			(end -0.2794 0.9906)
			(stroke
				(width 0.1)
				(type default)
			)
			(layer "B.Fab")
		)
		(pad "1" smd rect
			(at 0 0 180)
			(size 0.508 0.508)
			(layers "B.Cu" "B.Mask" "B.Paste")
			(net "FM_BEEP_LED_P")
		)
		(pad "2" smd rect
			(at 0 0.889 180)
			(size 0.508 0.508)
			(layers "B.Cu" "B.Mask" "B.Paste")
			(net "P3V3_STBY")
		)
		(zone
			(layer "B.Cu")
			(hatch none 0.5)
			(connect_pads
				(clearance 0)
			)
			(min_thickness 0.25)
			(keepout
				(tracks allowed)
				(vias not_allowed)
				(pads allowed)
				(copperpour not_allowed)
				(footprints allowed)
			)
			(placement
				(enabled no)
				(sheetname "")
			)
			(fill
				(thermal_gap 0.5)
				(thermal_bridge_width 0.5)
				(island_removal_mode 0)
			)
			(polygon
				(pts
					(xy 499.6434 -140.589) (xy 499.1354 -140.589) (xy 499.1354 -140.208) (xy 499.6434 -140.208)
				)
			)
		)
		(zone
			(layer "B.Cu")
			(hatch none 0.5)
			(connect_pads
				(clearance 0)
			)
			(min_thickness 0.25)
			(keepout
				(tracks not_allowed)
				(vias allowed)
				(pads allowed)
				(copperpour not_allowed)
				(footprints allowed)
			)
			(placement
				(enabled no)
				(sheetname "")
			)
			(fill
				(thermal_gap 0.5)
				(thermal_bridge_width 0.5)
				(island_removal_mode 0)
			)
			(polygon
				(pts
					(xy 499.6434 -140.208) (xy 499.1354 -140.208) (xy 499.1354 -140.589) (xy 499.6434 -140.589)
				)
			)
		)
	)
	(footprint ""
		(layer "B.Cu")
		(at 248.8565 -12.954 -90)
		(property "Reference" "C5G42"
			(at -1.14681 0.76708 0)
			(unlocked yes)
			(layer "B.SilkS")
			(effects
				(font
					(size 0.7874 0.5842)
					(thickness 0.1524)
				)
				(justify mirror)
			)
		)
		(property "Value" ""
			(at 0 0 90)
			(layer "B.Fab")
			(effects
				(font
					(size 1.27 1.27)
				)
				(justify mirror)
			)
		)
		(duplicate_pad_numbers_are_jumpers no)
		(fp_rect
			(start 0.4953 1.6002)
			(end -0.4953 -0.2032)
			(stroke
				(width 0)
				(type default)
			)
			(fill no)
			(layer "B.CrtYd")
		)
		(fp_line
			(start -0.4953 1.6002)
			(end 0.4953 1.6002)
			(stroke
				(width 0.1)
				(type default)
			)
			(layer "B.Fab")
		)
		(fp_line
			(start 0.4953 1.6002)
			(end 0.4953 -0.2032)
			(stroke
				(width 0.1)
				(type default)
			)
			(layer "B.Fab")
		)
		(fp_line
			(start -0.4953 -0.2032)
			(end -0.4953 1.6002)
			(stroke
				(width 0.1)
				(type default)
			)
			(layer "B.Fab")
		)
		(fp_line
			(start 0.4953 -0.2032)
			(end -0.4953 -0.2032)
			(stroke
				(width 0.1)
				(type default)
			)
			(layer "B.Fab")
		)
		(pad "1" smd rect
			(at 0 0 90)
			(size 0.762 0.889)
			(layers "B.Cu" "B.Mask" "B.Paste")
			(net "PVDDQ_ABC")
		)
		(pad "2" smd rect
			(at 0 1.397 90)
			(size 0.762 0.889)
			(layers "B.Cu" "B.Mask" "B.Paste")
			(net "GND")
		)
		(zone
			(layer "B.Cu")
			(hatch none 0.5)
			(connect_pads
				(clearance 0)
			)
			(min_thickness 0.25)
			(keepout
				(tracks not_allowed)
				(vias allowed)
				(pads allowed)
				(copperpour not_allowed)
				(footprints allowed)
			)
			(placement
				(enabled no)
				(sheetname "")
			)
			(fill
				(thermal_gap 0.5)
				(thermal_bridge_width 0.5)
				(island_removal_mode 0)
			)
			(polygon
				(pts
					(xy 247.904 -12.573) (xy 248.412 -12.573) (xy 248.412 -13.335) (xy 247.904 -13.335)
				)
			)
		)
	)
	(footprint ""
		(layer "B.Cu")
		(at 408.305 -151.511 90)
		(property "Reference" "C2L14"
			(at 0 0 90)
			(layer "B.SilkS")
			(hide yes)
			(effects
				(font
					(size 1.27 1.27)
				)
				(justify mirror)
			)
		)
		(property "Value" ""
			(at 0 0 90)
			(layer "B.Fab")
			(effects
				(font
					(size 1.27 1.27)
				)
				(justify mirror)
			)
		)
		(duplicate_pad_numbers_are_jumpers no)
		(fp_poly
			(pts
				(xy -0.3048 -0.1016) (xy -0.3048 0.9906) (xy 0.3048 0.9906) (xy 0.3048 -0.1016)
			)
			(stroke
				(width 0)
				(type default)
			)
			(fill no)
			(layer "B.CrtYd")
		)
		(fp_line
			(start 0.3048 -0.1016)
			(end 0.3048 0.9906)
			(stroke
				(width 0.1)
				(type default)
			)
			(layer "B.Fab")
		)
		(fp_line
			(start -0.3048 -0.1016)
			(end 0.3048 -0.1016)
			(stroke
				(width 0.1)
				(type default)
			)
			(layer "B.Fab")
		)
		(fp_line
			(start 0.3048 0.9906)
			(end -0.3048 0.9906)
			(stroke
				(width 0.1)
				(type default)
			)
			(layer "B.Fab")
		)
		(fp_line
			(start -0.3048 0.9906)
			(end -0.3048 -0.1016)
			(stroke
				(width 0.1)
				(type default)
			)
			(layer "B.Fab")
		)
		(pad "1" smd rect
			(at 0 0 270)
			(size 0.508 0.508)
			(layers "B.Cu" "B.Mask" "B.Paste")
			(net "SATA6G_PCH_PCIE_UP_SATA_RXN<6>")
		)
		(pad "2" smd rect
			(at 0 0.889 270)
			(size 0.508 0.508)
			(layers "B.Cu" "B.Mask" "B.Paste")
			(net "SATA6G_P6_RX_C_DN")
		)
		(zone
			(layer "B.Cu")
			(hatch none 0.5)
			(connect_pads
				(clearance 0)
			)
			(min_thickness 0.25)
			(keepout
				(tracks allowed)
				(vias not_allowed)
				(pads allowed)
				(copperpour not_allowed)
				(footprints allowed)
			)
			(placement
				(enabled no)
				(sheetname "")
			)
			(fill
				(thermal_gap 0.5)
				(thermal_bridge_width 0.5)
				(island_removal_mode 0)
			)
			(polygon
				(pts
					(xy 408.559 -151.765) (xy 408.559 -151.257) (xy 408.94 -151.257) (xy 408.94 -151.765)
				)
			)
		)
		(zone
			(layer "B.Cu")
			(hatch none 0.5)
			(connect_pads
				(clearance 0)
			)
			(min_thickness 0.25)
			(keepout
				(tracks not_allowed)
				(vias allowed)
				(pads allowed)
				(copperpour not_allowed)
				(footprints allowed)
			)
			(placement
				(enabled no)
				(sheetname "")
			)
			(fill
				(thermal_gap 0.5)
				(thermal_bridge_width 0.5)
				(island_removal_mode 0)
			)
			(polygon
				(pts
					(xy 408.94 -151.765) (xy 408.94 -151.257) (xy 408.559 -151.257) (xy 408.559 -151.765)
				)
			)
		)
	)
	(footprint ""
		(layer "B.Cu")
		(at 330.091288 -64.17564 90)
		(property "Reference" "R3R13"
			(at 0 0 90)
			(layer "B.SilkS")
			(hide yes)
			(effects
				(font
					(size 1.27 1.27)
				)
				(justify mirror)
			)
		)
		(property "Value" ""
			(at 0 0 90)
			(layer "B.Fab")
			(effects
				(font
					(size 1.27 1.27)
				)
				(justify mirror)
			)
		)
		(duplicate_pad_numbers_are_jumpers no)
		(fp_poly
			(pts
				(xy 0.2794 -0.1016) (xy -0.2794 -0.1016) (xy -0.2794 0.9906) (xy 0.2794 0.9906)
			)
			(stroke
				(width 0)
				(type default)
			)
			(fill no)
			(layer "B.CrtYd")
		)
		(fp_line
			(start 0.2794 -0.1016)
			(end 0.2794 0.9906)
			(stroke
				(width 0.1)
				(type default)
			)
			(layer "B.Fab")
		)
		(fp_line
			(start -0.2794 -0.1016)
			(end 0.2794 -0.1016)
			(stroke
				(width 0.1)
				(type default)
			)
			(layer "B.Fab")
		)
		(fp_line
			(start 0.2794 0.9906)
			(end -0.2794 0.9906)
			(stroke
				(width 0.1)
				(type default)
			)
			(layer "B.Fab")
		)
		(fp_line
			(start -0.2794 0.9906)
			(end -0.2794 -0.1016)
			(stroke
				(width 0.1)
				(type default)
			)
			(layer "B.Fab")
		)
		(pad "1" smd rect
			(at 0 0 270)
			(size 0.508 0.508)
			(layers "B.Cu" "B.Mask" "B.Paste")
			(net "PVCCIO_CPU0")
		)
		(pad "2" smd rect
			(at 0 0.889 270)
			(size 0.508 0.508)
			(layers "B.Cu" "B.Mask" "B.Paste")
			(net "SMB_DDR_DEF_SDA_G")
		)
		(zone
			(layer "B.Cu")
			(hatch none 0.5)
			(connect_pads
				(clearance 0)
			)
			(min_thickness 0.25)
			(keepout
				(tracks allowed)
				(vias not_allowed)
				(pads allowed)
				(copperpour not_allowed)
				(footprints allowed)
			)
			(placement
				(enabled no)
				(sheetname "")
			)
			(fill
				(thermal_gap 0.5)
				(thermal_bridge_width 0.5)
				(island_removal_mode 0)
			)
			(polygon
				(pts
					(xy 330.345288 -64.42964) (xy 330.345288 -63.92164) (xy 330.726288 -63.92164) (xy 330.726288 -64.42964)
				)
			)
		)
		(zone
			(layer "B.Cu")
			(hatch none 0.5)
			(connect_pads
				(clearance 0)
			)
			(min_thickness 0.25)
			(keepout
				(tracks not_allowed)
				(vias allowed)
				(pads allowed)
				(copperpour not_allowed)
				(footprints allowed)
			)
			(placement
				(enabled no)
				(sheetname "")
			)
			(fill
				(thermal_gap 0.5)
				(thermal_bridge_width 0.5)
				(island_removal_mode 0)
			)
			(polygon
				(pts
					(xy 330.726288 -64.42964) (xy 330.726288 -63.92164) (xy 330.345288 -63.92164) (xy 330.345288 -64.42964)
				)
			)
		)
	)
	(footprint ""
		(layer "B.Cu")
		(at 173.279816 -68.650104 180)
		(property "Reference" "Q4W2"
			(at 0.229362 -1.59512 180)
			(unlocked yes)
			(layer "B.SilkS")
			(effects
				(font
					(size 1.27 0.9652)
					(thickness 0.1524)
				)
				(justify left mirror)
			)
		)
		(property "Value" ""
			(at 0 0 0)
			(layer "B.Fab")
			(effects
				(font
					(size 1.27 1.27)
				)
				(justify mirror)
			)
		)
		(duplicate_pad_numbers_are_jumpers no)
		(fp_line
			(start -0.381 0.635)
			(end -0.381 1.27)
			(stroke
				(width 0.1524)
				(type default)
			)
			(layer "B.SilkS")
		)
		(fp_line
			(start -0.9525 2.4765)
			(end -1.778 2.4765)
			(stroke
				(width 0.1524)
				(type default)
			)
			(layer "B.SilkS")
		)
		(fp_line
			(start -0.9525 -0.5715)
			(end -1.778 -0.5715)
			(stroke
				(width 0.1524)
				(type default)
			)
			(layer "B.SilkS")
		)
		(fp_line
			(start -1.778 2.4765)
			(end -1.778 1.5875)
			(stroke
				(width 0.1524)
				(type default)
			)
			(layer "B.SilkS")
		)
		(fp_line
			(start -1.778 -0.5715)
			(end -1.778 0.3175)
			(stroke
				(width 0.1524)
				(type default)
			)
			(layer "B.SilkS")
		)
		(fp_circle
			(center 0.9525 -0.9271)
			(end 0.8255 -0.9271)
			(stroke
				(width 0.254)
				(type default)
			)
			(fill no)
			(layer "B.SilkS")
		)
		(fp_poly
			(pts
				(xy -1.778 2.4765) (xy -0.381 2.4765) (xy -0.381 -0.5715) (xy -1.778 -0.5715)
			)
			(stroke
				(width 0)
				(type default)
			)
			(fill no)
			(layer "B.CrtYd")
		)
		(fp_line
			(start -0.381 2.4765)
			(end -1.778 2.4765)
			(stroke
				(width 0.1)
				(type default)
			)
			(layer "B.Fab")
		)
		(fp_line
			(start -0.381 -0.5715)
			(end -0.381 2.4765)
			(stroke
				(width 0.1)
				(type default)
			)
			(layer "B.Fab")
		)
		(fp_line
			(start -1.778 2.4765)
			(end -1.778 -0.5715)
			(stroke
				(width 0.1)
				(type default)
			)
			(layer "B.Fab")
		)
		(fp_line
			(start -1.778 -0.5715)
			(end -0.381 -0.5715)
			(stroke
				(width 0.1)
				(type default)
			)
			(layer "B.Fab")
		)
		(fp_circle
			(center 0.9525 -0.9271)
			(end 0.8255 -0.9271)
			(stroke
				(width 0.254)
				(type default)
			)
			(fill no)
			(layer "B.Fab")
		)
		(pad "1" smd rect
			(at 0 0)
			(size 1.143 0.508)
			(layers "B.Cu" "B.Mask" "B.Paste")
			(net "FM_DB1200_PWRGD")
		)
		(pad "2" smd rect
			(at 0 1.905)
			(size 1.143 0.508)
			(layers "B.Cu" "B.Mask" "B.Paste")
			(net "GND")
		)
		(pad "3" smd rect
			(at -2.159 0.9525)
			(size 1.143 0.508)
			(layers "B.Cu" "B.Mask" "B.Paste")
			(net "FM_DB1200_PWRGD_R")
		)
	)
	(footprint ""
		(layer "B.Cu")
		(at 245.7577 -135.4074 -90)
		(property "Reference" "C5M7"
			(at -1.848866 0.752348 270)
			(unlocked yes)
			(layer "B.SilkS")
			(effects
				(font
					(size 1.27 0.9652)
					(thickness 0.1524)
				)
				(justify mirror)
			)
		)
		(property "Value" ""
			(at 0 0 90)
			(layer "B.Fab")
			(effects
				(font
					(size 1.27 1.27)
				)
				(justify mirror)
			)
		)
		(duplicate_pad_numbers_are_jumpers no)
		(fp_rect
			(start 0.500126 1.598422)
			(end -0.500126 -0.201422)
			(stroke
				(width 0)
				(type default)
			)
			(fill no)
			(layer "B.CrtYd")
		)
		(fp_line
			(start -0.500126 1.598422)
			(end 0.500126 1.598422)
			(stroke
				(width 0.1)
				(type default)
			)
			(layer "B.Fab")
		)
		(fp_line
			(start 0.500126 1.598422)
			(end 0.500126 -0.201422)
			(stroke
				(width 0.1)
				(type default)
			)
			(layer "B.Fab")
		)
		(fp_line
			(start -0.500126 -0.201422)
			(end -0.500126 1.598422)
			(stroke
				(width 0.1)
				(type default)
			)
			(layer "B.Fab")
		)
		(fp_line
			(start 0.500126 -0.201422)
			(end -0.500126 -0.201422)
			(stroke
				(width 0.1)
				(type default)
			)
			(layer "B.Fab")
		)
		(pad "1" smd rect
			(at 0 0 180)
			(size 0.889 0.9906)
			(layers "B.Cu" "B.Mask" "B.Paste")
			(net "PVDDQ_DEF")
		)
		(pad "2" smd rect
			(at 0 1.397 180)
			(size 0.889 0.9906)
			(layers "B.Cu" "B.Mask" "B.Paste")
			(net "GND")
		)
		(zone
			(layer "B.Cu")
			(hatch none 0.5)
			(connect_pads
				(clearance 0)
			)
			(min_thickness 0.25)
			(keepout
				(tracks not_allowed)
				(vias allowed)
				(pads allowed)
				(copperpour not_allowed)
				(footprints allowed)
			)
			(placement
				(enabled no)
				(sheetname "")
			)
			(fill
				(thermal_gap 0.5)
				(thermal_bridge_width 0.5)
				(island_removal_mode 0)
			)
			(polygon
				(pts
					(xy 244.8052 -134.9121) (xy 245.3132 -134.9121) (xy 245.3132 -135.9027) (xy 244.8052 -135.9027)
				)
			)
		)
		(zone
			(layer "B.Cu")
			(hatch none 0.5)
			(connect_pads
				(clearance 0)
			)
			(min_thickness 0.25)
			(keepout
				(tracks allowed)
				(vias not_allowed)
				(pads allowed)
				(copperpour not_allowed)
				(footprints allowed)
			)
			(placement
				(enabled no)
				(sheetname "")
			)
			(fill
				(thermal_gap 0.5)
				(thermal_bridge_width 0.5)
				(island_removal_mode 0)
			)
			(polygon
				(pts
					(xy 244.8052 -134.9121) (xy 245.3132 -134.9121) (xy 245.3132 -135.9027) (xy 244.8052 -135.9027)
				)
			)
		)
	)
	(footprint ""
		(layer "B.Cu")
		(at 197.848728 -58.428382 90)
		(property "Reference" "C6R11"
			(at 0 0 90)
			(layer "B.SilkS")
			(hide yes)
			(effects
				(font
					(size 1.27 1.27)
				)
				(justify mirror)
			)
		)
		(property "Value" ""
			(at 0 0 90)
			(layer "B.Fab")
			(effects
				(font
					(size 1.27 1.27)
				)
				(justify mirror)
			)
		)
		(duplicate_pad_numbers_are_jumpers no)
		(fp_rect
			(start 0.7239 1.9939)
			(end -0.7239 -0.2159)
			(stroke
				(width 0)
				(type default)
			)
			(fill no)
			(layer "B.CrtYd")
		)
		(fp_line
			(start 0.7239 -0.2159)
			(end 0.7239 1.9939)
			(stroke
				(width 0.1)
				(type default)
			)
			(layer "B.Fab")
		)
		(fp_line
			(start -0.7239 -0.2159)
			(end 0.7239 -0.2159)
			(stroke
				(width 0.1)
				(type default)
			)
			(layer "B.Fab")
		)
		(fp_line
			(start 0.7239 1.9939)
			(end -0.7239 1.9939)
			(stroke
				(width 0.1)
				(type default)
			)
			(layer "B.Fab")
		)
		(fp_line
			(start -0.7239 1.9939)
			(end -0.7239 -0.2159)
			(stroke
				(width 0.1)
				(type default)
			)
			(layer "B.Fab")
		)
		(pad "1" smd rect
			(at 0 0 270)
			(size 1.27 1.016)
			(layers "B.Cu" "B.Mask" "B.Paste")
			(net "VR_FET_SW_P12V_STBY_PVCCIN_CPU0")
		)
		(pad "2" smd rect
			(at 0 1.778 270)
			(size 1.27 1.016)
			(layers "B.Cu" "B.Mask" "B.Paste")
			(net "GND")
		)
		(zone
			(layer "B.Cu")
			(hatch none 0.5)
			(connect_pads
				(clearance 0)
			)
			(min_thickness 0.25)
			(keepout
				(tracks not_allowed)
				(vias allowed)
				(pads allowed)
				(copperpour not_allowed)
				(footprints allowed)
			)
			(placement
				(enabled no)
				(sheetname "")
			)
			(fill
				(thermal_gap 0.5)
				(thermal_bridge_width 0.5)
				(island_removal_mode 0)
			)
			(polygon
				(pts
					(xy 199.118728 -59.063382) (xy 198.356728 -59.063382) (xy 198.356728 -57.793382) (xy 199.118728 -57.793382)
				)
			)
		)
	)
	(footprint ""
		(layer "B.Cu")
		(at 111.836454 -77.82814)
		(property "Reference" "C7P8"
			(at 0 0 0)
			(layer "B.SilkS")
			(hide yes)
			(effects
				(font
					(size 1.27 1.27)
				)
				(justify mirror)
			)
		)
		(property "Value" ""
			(at 0 0 0)
			(layer "B.Fab")
			(effects
				(font
					(size 1.27 1.27)
				)
				(justify mirror)
			)
		)
		(duplicate_pad_numbers_are_jumpers no)
		(fp_poly
			(pts
				(xy 0.7239 -0.2159) (xy -0.7239 -0.2159) (xy -0.7239 1.9939) (xy 0.7239 1.9939)
			)
			(stroke
				(width 0)
				(type default)
			)
			(fill no)
			(layer "B.CrtYd")
		)
		(fp_line
			(start -0.7239 -0.2159)
			(end 0.7239 -0.2159)
			(stroke
				(width 0.1)
				(type default)
			)
			(layer "B.Fab")
		)
		(fp_line
			(start -0.7239 1.9939)
			(end -0.7239 -0.2159)
			(stroke
				(width 0.1)
				(type default)
			)
			(layer "B.Fab")
		)
		(fp_line
			(start 0.7239 -0.2159)
			(end 0.7239 1.9939)
			(stroke
				(width 0.1)
				(type default)
			)
			(layer "B.Fab")
		)
		(fp_line
			(start 0.7239 1.9939)
			(end -0.7239 1.9939)
			(stroke
				(width 0.1)
				(type default)
			)
			(layer "B.Fab")
		)
		(pad "1" smd rect
			(at 0 0 180)
			(size 1.27 1.016)
			(layers "B.Cu" "B.Mask" "B.Paste")
			(net "PVCCMCP_CPU1")
		)
		(pad "2" smd rect
			(at 0 1.778 180)
			(size 1.27 1.016)
			(layers "B.Cu" "B.Mask" "B.Paste")
			(net "GND")
		)
		(zone
			(layer "B.Cu")
			(hatch none 0.5)
			(connect_pads
				(clearance 0)
			)
			(min_thickness 0.25)
			(keepout
				(tracks not_allowed)
				(vias allowed)
				(pads allowed)
				(copperpour not_allowed)
				(footprints allowed)
			)
			(placement
				(enabled no)
				(sheetname "")
			)
			(fill
				(thermal_gap 0.5)
				(thermal_bridge_width 0.5)
				(island_removal_mode 0)
			)
			(polygon
				(pts
					(xy 112.471454 -77.32014) (xy 111.201454 -77.32014) (xy 111.201454 -76.55814) (xy 112.471454 -76.55814)
				)
			)
		)
	)
)
